(kicad_pcb
	(version 20260206)
	(generator "pcbnew")
	(generator_version "10.0")
	(general
		(thickness 1.6)
		(legacy_teardrops no)
	)
	(paper "A4")
	(title_block
		(title "01162023_DA0F0TEBIF0_F0T_Expander_BD_F_brd_V02_OCP.brd")
		(comment 1 "Grand Teton / footprints 1869-1873 of 9728")
	)
	(layers
		(0 "F.Cu" signal "TOP")
		(4 "In1.Cu" signal "GND")
		(6 "In2.Cu" signal "VCC")
		(8 "In3.Cu" signal "VCC1")
		(10 "In4.Cu" signal "GND1")
		(12 "In5.Cu" signal "IN1")
		(14 "In6.Cu" signal "GND2")
		(16 "In7.Cu" signal "IN2")
		(18 "In8.Cu" signal "GND3")
		(20 "In9.Cu" signal "IN3")
		(22 "In10.Cu" signal "GND4")
		(24 "In11.Cu" signal "IN4")
		(26 "In12.Cu" signal "GND5")
		(28 "In13.Cu" signal "IN5")
		(30 "In14.Cu" signal "GND6")
		(32 "In15.Cu" signal "IN6")
		(34 "In16.Cu" signal "GND7")
		(2 "B.Cu" signal "BOTTOM")
		(9 "F.Adhes" user "F.Adhesive")
		(11 "B.Adhes" user "B.Adhesive")
		(13 "F.Paste" user "Package Geometry/Pastemask Top")
		(15 "B.Paste" user "Package Geometry/Pastemask Bottom")
		(5 "F.SilkS" user "Ref Des/Silkscreen Top")
		(7 "B.SilkS" user "Ref Des/Silkscreen Bottom")
		(1 "F.Mask" user "Board Geometry/Soldermask Top")
		(3 "B.Mask" user "Board Geometry/Soldermask Bottom")
		(17 "Dwgs.User" user "User.Drawings")
		(19 "Cmts.User" user "User.Comments")
		(21 "Eco1.User" user "User.Eco1")
		(23 "Eco2.User" user "User.Eco2")
		(25 "Edge.Cuts" user "Board Geometry/Outline")
		(27 "Margin" user)
		(31 "F.CrtYd" user "Package Geometry/Place Bound Top")
		(29 "B.CrtYd" user "Package Geometry/Place Bound Bottom")
		(35 "F.Fab" user "Ref Des/Assembly Top")
		(33 "B.Fab" user "Ref Des/Assembly Bottom")
	)
	(footprint ""
		(layer "F.Cu")
		(at 426.567854 -52.035456 180)
		(property "Reference" "R874"
			(at 0 0 180)
			(layer "F.SilkS")
			(hide yes)
			(effects
				(font
					(size 1.27 1.27)
				)
			)
		)
		(property "Value" ""
			(at 0 0 180)
			(layer "F.Fab")
			(effects
				(font
					(size 1.27 1.27)
				)
			)
		)
		(duplicate_pad_numbers_are_jumpers no)
		(fp_line
			(start 0.7874 0.4064)
			(end -0.7874 0.4064)
			(stroke
				(width 0.1524)
				(type default)
			)
			(layer "F.SilkS")
		)
		(fp_line
			(start 0.7874 -0.4064)
			(end 0.7874 0.4064)
			(stroke
				(width 0.1524)
				(type default)
			)
			(layer "F.SilkS")
		)
		(fp_line
			(start -0.7874 0.4064)
			(end -0.7874 -0.4064)
			(stroke
				(width 0.1524)
				(type default)
			)
			(layer "F.SilkS")
		)
		(fp_line
			(start -0.7874 -0.4064)
			(end 0.7874 -0.4064)
			(stroke
				(width 0.1524)
				(type default)
			)
			(layer "F.SilkS")
		)
		(fp_line
			(start 0.67945 0.3048)
			(end 0.120396 0.3048)
			(stroke
				(width 0.1)
				(type default)
			)
			(layer "F.Fab")
		)
		(fp_line
			(start 0.67945 -0.3048)
			(end 0.67945 0.3048)
			(stroke
				(width 0.1)
				(type default)
			)
			(layer "F.Fab")
		)
		(fp_line
			(start 0.12065 -0.2794)
			(end 0.12065 -0.3048)
			(stroke
				(width 0.1)
				(type default)
			)
			(layer "F.Fab")
		)
		(fp_line
			(start 0.12065 -0.3048)
			(end 0.67945 -0.3048)
			(stroke
				(width 0.1)
				(type default)
			)
			(layer "F.Fab")
		)
		(fp_line
			(start 0.120396 0.3048)
			(end 0.120396 0.2794)
			(stroke
				(width 0.1)
				(type default)
			)
			(layer "F.Fab")
		)
		(fp_line
			(start 0.120396 0.2794)
			(end -0.12065 0.2794)
			(stroke
				(width 0.1)
				(type default)
			)
			(layer "F.Fab")
		)
		(fp_line
			(start -0.12065 0.3048)
			(end -0.67945 0.3048)
			(stroke
				(width 0.1)
				(type default)
			)
			(layer "F.Fab")
		)
		(fp_line
			(start -0.12065 0.2794)
			(end -0.12065 0.3048)
			(stroke
				(width 0.1)
				(type default)
			)
			(layer "F.Fab")
		)
		(fp_line
			(start -0.12065 -0.2794)
			(end 0.12065 -0.2794)
			(stroke
				(width 0.1)
				(type default)
			)
			(layer "F.Fab")
		)
		(fp_line
			(start -0.12065 -0.305054)
			(end -0.12065 -0.2794)
			(stroke
				(width 0.1)
				(type default)
			)
			(layer "F.Fab")
		)
		(fp_line
			(start -0.67945 0.3048)
			(end -0.67945 -0.305054)
			(stroke
				(width 0.1)
				(type default)
			)
			(layer "F.Fab")
		)
		(fp_line
			(start -0.67945 -0.305054)
			(end -0.12065 -0.305054)
			(stroke
				(width 0.1)
				(type default)
			)
			(layer "F.Fab")
		)
		(pad "1" smd circle
			(at -0.40005 0 180)
			(size 0 0)
			(layers "F.Cu" "F.Mask" "F.Paste")
			(net "P3V3_AUX")
		)
		(pad "2" smd circle
			(at 0.40005 0 180)
			(size 0 0)
			(layers "F.Cu" "F.Mask" "F.Paste")
			(net "PWRGD_P12V_SSD14")
		)
	)
	(footprint ""
		(layer "F.Cu")
		(at 124.32919 -110.722918 -90)
		(property "Reference" "R5828"
			(at 0 0 270)
			(layer "F.SilkS")
			(hide yes)
			(effects
				(font
					(size 1.27 1.27)
				)
			)
		)
		(property "Value" ""
			(at 0 0 270)
			(layer "F.Fab")
			(effects
				(font
					(size 1.27 1.27)
				)
			)
		)
		(duplicate_pad_numbers_are_jumpers no)
		(fp_line
			(start -0.7874 0.4064)
			(end -0.7874 -0.4064)
			(stroke
				(width 0.1524)
				(type default)
			)
			(layer "F.SilkS")
		)
		(fp_line
			(start 0.7874 0.4064)
			(end -0.7874 0.4064)
			(stroke
				(width 0.1524)
				(type default)
			)
			(layer "F.SilkS")
		)
		(fp_line
			(start -0.7874 -0.4064)
			(end 0.7874 -0.4064)
			(stroke
				(width 0.1524)
				(type default)
			)
			(layer "F.SilkS")
		)
		(fp_line
			(start 0.7874 -0.4064)
			(end 0.7874 0.4064)
			(stroke
				(width 0.1524)
				(type default)
			)
			(layer "F.SilkS")
		)
		(fp_line
			(start -0.67945 0.3048)
			(end -0.67945 -0.305054)
			(stroke
				(width 0.1)
				(type default)
			)
			(layer "F.Fab")
		)
		(fp_line
			(start -0.12065 0.3048)
			(end -0.67945 0.3048)
			(stroke
				(width 0.1)
				(type default)
			)
			(layer "F.Fab")
		)
		(fp_line
			(start 0.120396 0.3048)
			(end 0.120396 0.2794)
			(stroke
				(width 0.1)
				(type default)
			)
			(layer "F.Fab")
		)
		(fp_line
			(start 0.67945 0.3048)
			(end 0.120396 0.3048)
			(stroke
				(width 0.1)
				(type default)
			)
			(layer "F.Fab")
		)
		(fp_line
			(start -0.12065 0.2794)
			(end -0.12065 0.3048)
			(stroke
				(width 0.1)
				(type default)
			)
			(layer "F.Fab")
		)
		(fp_line
			(start 0.120396 0.2794)
			(end -0.12065 0.2794)
			(stroke
				(width 0.1)
				(type default)
			)
			(layer "F.Fab")
		)
		(fp_line
			(start -0.12065 -0.2794)
			(end 0.12065 -0.2794)
			(stroke
				(width 0.1)
				(type default)
			)
			(layer "F.Fab")
		)
		(fp_line
			(start 0.12065 -0.2794)
			(end 0.12065 -0.3048)
			(stroke
				(width 0.1)
				(type default)
			)
			(layer "F.Fab")
		)
		(fp_line
			(start 0.12065 -0.3048)
			(end 0.67945 -0.3048)
			(stroke
				(width 0.1)
				(type default)
			)
			(layer "F.Fab")
		)
		(fp_line
			(start 0.67945 -0.3048)
			(end 0.67945 0.3048)
			(stroke
				(width 0.1)
				(type default)
			)
			(layer "F.Fab")
		)
		(fp_line
			(start -0.67945 -0.305054)
			(end -0.12065 -0.305054)
			(stroke
				(width 0.1)
				(type default)
			)
			(layer "F.Fab")
		)
		(fp_line
			(start -0.12065 -0.305054)
			(end -0.12065 -0.2794)
			(stroke
				(width 0.1)
				(type default)
			)
			(layer "F.Fab")
		)
		(pad "1" smd circle
			(at -0.40005 0 270)
			(size 0 0)
			(layers "F.Cu" "F.Mask" "F.Paste")
			(net "P3V3")
		)
		(pad "2" smd circle
			(at 0.40005 0 270)
			(size 0 0)
			(layers "F.Cu" "F.Mask" "F.Paste")
			(net "P3V3_PG_G1")
		)
	)
	(footprint ""
		(layer "F.Cu")
		(at 208.300066 -98.700082)
		(property "Reference" "H79"
			(at -6.217666 -7.419848 0)
			(unlocked yes)
			(layer "F.SilkS")
			(effects
				(font
					(size 0.7874 0.5842)
					(thickness 0.1524)
				)
				(justify left)
			)
		)
		(property "Value" ""
			(at 0 0 0)
			(layer "F.Fab")
			(effects
				(font
					(size 1.27 1.27)
				)
			)
		)
		(duplicate_pad_numbers_are_jumpers no)
		(fp_circle
			(center 0 0)
			(end 7.999984 0)
			(stroke
				(width 0.1524)
				(type default)
			)
			(fill no)
			(layer "F.SilkS")
		)
		(fp_circle
			(center 0 0)
			(end 7.999984 0)
			(stroke
				(width 0.1524)
				(type default)
			)
			(fill no)
			(layer "B.SilkS")
		)
		(fp_circle
			(center 0 0)
			(end 7.999984 0)
			(stroke
				(width 0.1)
				(type default)
			)
			(fill no)
			(layer "B.Fab")
		)
		(fp_circle
			(center 0 0)
			(end 7.999984 0)
			(stroke
				(width 0.1)
				(type default)
			)
			(fill no)
			(layer "F.Fab")
		)
		(pad "" np_thru_hole circle
			(at 0 0)
			(size 3.4036 3.4036)
			(drill 3.4036)
			(layers "*.Cu" "*.Mask")
			(clearance 0.381)
			(thermal_gap 0.381)
		)
		(pad "2" thru_hole circle
			(at 3.606292 0)
			(size 0.762 0.762)
			(drill 0.5588)
			(layers "*.Cu" "*.Mask")
			(remove_unused_layers no)
			(net "GND")
			(clearance 0.1524)
			(thermal_gap 0.1524)
		)
		(pad "3" thru_hole circle
			(at 2.549906 -2.549906)
			(size 0.762 0.762)
			(drill 0.5588)
			(layers "*.Cu" "*.Mask")
			(remove_unused_layers no)
			(net "GND")
			(clearance 0.1524)
			(thermal_gap 0.1524)
		)
		(pad "4" thru_hole circle
			(at 0 -3.606292)
			(size 0.762 0.762)
			(drill 0.5588)
			(layers "*.Cu" "*.Mask")
			(remove_unused_layers no)
			(net "GND")
			(clearance 0.1524)
			(thermal_gap 0.1524)
		)
		(pad "5" thru_hole circle
			(at -2.549906 -2.549906)
			(size 0.762 0.762)
			(drill 0.5588)
			(layers "*.Cu" "*.Mask")
			(remove_unused_layers no)
			(net "GND")
			(clearance 0.1524)
			(thermal_gap 0.1524)
		)
		(pad "6" thru_hole circle
			(at -3.606292 0)
			(size 0.762 0.762)
			(drill 0.5588)
			(layers "*.Cu" "*.Mask")
			(remove_unused_layers no)
			(net "GND")
			(clearance 0.1524)
			(thermal_gap 0.1524)
		)
		(pad "7" thru_hole circle
			(at -2.549906 2.549906)
			(size 0.762 0.762)
			(drill 0.5588)
			(layers "*.Cu" "*.Mask")
			(remove_unused_layers no)
			(net "GND")
			(clearance 0.1524)
			(thermal_gap 0.1524)
		)
		(pad "8" thru_hole circle
			(at 0 3.606292)
			(size 0.762 0.762)
			(drill 0.5588)
			(layers "*.Cu" "*.Mask")
			(remove_unused_layers no)
			(net "GND")
			(clearance 0.1524)
			(thermal_gap 0.1524)
		)
		(pad "9" thru_hole circle
			(at 2.549906 2.549906)
			(size 0.762 0.762)
			(drill 0.5588)
			(layers "*.Cu" "*.Mask")
			(remove_unused_layers no)
			(net "GND")
			(clearance 0.1524)
			(thermal_gap 0.1524)
		)
		(zone
			(layer "F.Cu")
			(hatch none 0.5)
			(connect_pads
				(clearance 0)
			)
			(min_thickness 0.25)
			(keepout
				(tracks not_allowed)
				(vias allowed)
				(pads allowed)
				(copperpour not_allowed)
				(footprints allowed)
			)
			(placement
				(enabled no)
				(sheetname "")
			)
			(fill
				(thermal_gap 0.5)
				(thermal_bridge_width 0.5)
				(island_removal_mode 0)
			)
			(polygon
				(pts
					(arc
						(start 208.300066 -90.700098)
						(mid 200.300082 -98.700082)
						(end 208.300066 -106.700066)
					)
					(arc
						(start 208.300066 -103.954072)
						(mid 203.046076 -98.700082)
						(end 208.300066 -93.446092)
					)
				)
			)
		)
		(zone
			(layer "F.Cu")
			(hatch none 0.5)
			(connect_pads
				(clearance 0)
			)
			(min_thickness 0.25)
			(keepout
				(tracks not_allowed)
				(vias allowed)
				(pads allowed)
				(copperpour not_allowed)
				(footprints allowed)
			)
			(placement
				(enabled no)
				(sheetname "")
			)
			(fill
				(thermal_gap 0.5)
				(thermal_bridge_width 0.5)
				(island_removal_mode 0)
			)
			(polygon
				(pts
					(arc
						(start 208.300066 -90.700098)
						(mid 216.30005 -98.700082)
						(end 208.300066 -106.700066)
					)
					(arc
						(start 208.300066 -103.954072)
						(mid 213.554056 -98.700082)
						(end 208.300066 -93.446092)
					)
				)
			)
		)
		(zone
			(layers "F.Cu" "B.Cu" "In1.Cu" "In2.Cu" "In3.Cu" "In4.Cu" "In5.Cu" "In6.Cu"
				"In7.Cu" "In8.Cu" "In9.Cu" "In10.Cu" "In11.Cu" "In12.Cu" "In13.Cu" "In14.Cu"
				"In15.Cu" "In16.Cu"
			)
			(hatch none 0.5)
			(connect_pads
				(clearance 0)
			)
			(min_thickness 0.25)
			(keepout
				(tracks not_allowed)
				(vias allowed)
				(pads allowed)
				(copperpour not_allowed)
				(footprints allowed)
			)
			(placement
				(enabled no)
				(sheetname "")
			)
			(fill
				(thermal_gap 0.5)
				(thermal_bridge_width 0.5)
				(island_removal_mode 0)
			)
			(polygon
				(pts
					(arc
						(start 210.509866 -98.700082)
						(mid 206.090266 -98.700082)
						(end 210.509866 -98.700082)
					)
				)
			)
		)
		(zone
			(layer "B.Cu")
			(hatch none 0.5)
			(connect_pads
				(clearance 0)
			)
			(min_thickness 0.25)
			(keepout
				(tracks not_allowed)
				(vias allowed)
				(pads allowed)
				(copperpour not_allowed)
				(footprints allowed)
			)
			(placement
				(enabled no)
				(sheetname "")
			)
			(fill
				(thermal_gap 0.5)
				(thermal_bridge_width 0.5)
				(island_removal_mode 0)
			)
			(polygon
				(pts
					(arc
						(start 208.300066 -93.192092)
						(mid 202.792076 -98.700082)
						(end 208.300066 -104.208072)
					)
					(arc
						(start 208.300066 -103.725472)
						(mid 203.274676 -98.700082)
						(end 208.300066 -93.674692)
					)
				)
			)
		)
		(zone
			(layer "B.Cu")
			(hatch none 0.5)
			(connect_pads
				(clearance 0)
			)
			(min_thickness 0.25)
			(keepout
				(tracks not_allowed)
				(vias allowed)
				(pads allowed)
				(copperpour not_allowed)
				(footprints allowed)
			)
			(placement
				(enabled no)
				(sheetname "")
			)
			(fill
				(thermal_gap 0.5)
				(thermal_bridge_width 0.5)
				(island_removal_mode 0)
			)
			(polygon
				(pts
					(arc
						(start 208.300066 -93.192092)
						(mid 213.808056 -98.700082)
						(end 208.300066 -104.208072)
					)
					(arc
						(start 208.300066 -103.725472)
						(mid 213.325456 -98.700082)
						(end 208.300066 -93.674692)
					)
				)
			)
		)
	)
	(footprint ""
		(layer "F.Cu")
		(at 95.79229 -28.225242 180)
		(property "Reference" "C96"
			(at 0 0 180)
			(layer "F.SilkS")
			(hide yes)
			(effects
				(font
					(size 1.27 1.27)
				)
			)
		)
		(property "Value" ""
			(at 0 0 180)
			(layer "F.Fab")
			(effects
				(font
					(size 1.27 1.27)
				)
			)
		)
		(duplicate_pad_numbers_are_jumpers no)
		(fp_line
			(start 0.299974 0.150114)
			(end -0.299974 0.150114)
			(stroke
				(width 0.1)
				(type default)
			)
			(layer "F.Fab")
		)
		(fp_line
			(start 0.299974 -0.150114)
			(end 0.299974 0.150114)
			(stroke
				(width 0.1)
				(type default)
			)
			(layer "F.Fab")
		)
		(fp_line
			(start -0.299974 0.150114)
			(end -0.299974 -0.150114)
			(stroke
				(width 0.1)
				(type default)
			)
			(layer "F.Fab")
		)
		(fp_line
			(start -0.299974 -0.150114)
			(end 0.299974 -0.150114)
			(stroke
				(width 0.1)
				(type default)
			)
			(layer "F.Fab")
		)
		(pad "1" smd rect
			(at -0.2667 0 180)
			(size 0.3048 0.381)
			(layers "F.Cu" "F.Mask" "F.Paste")
			(net "P5E_PEX0_STN2_TX_DN<32>")
		)
		(pad "2" smd rect
			(at 0.2667 0 180)
			(size 0.3048 0.381)
			(layers "F.Cu" "F.Mask" "F.Paste")
			(net "P5E_PEX0_STN2_TX_C_DN<32>")
		)
	)
	(footprint ""
		(layer "F.Cu")
		(at 151.335486 -390.398254 90)
		(property "Reference" "R1837"
			(at 0 0 90)
			(layer "F.SilkS")
			(hide yes)
			(effects
				(font
					(size 1.27 1.27)
				)
			)
		)
		(property "Value" ""
			(at 0 0 90)
			(layer "F.Fab")
			(effects
				(font
					(size 1.27 1.27)
				)
			)
		)
		(duplicate_pad_numbers_are_jumpers no)
		(fp_line
			(start 0.7874 -0.4064)
			(end 0.7874 0.4064)
			(stroke
				(width 0.1524)
				(type default)
			)
			(layer "F.SilkS")
		)
		(fp_line
			(start -0.7874 -0.4064)
			(end 0.7874 -0.4064)
			(stroke
				(width 0.1524)
				(type default)
			)
			(layer "F.SilkS")
		)
		(fp_line
			(start 0.7874 0.4064)
			(end -0.7874 0.4064)
			(stroke
				(width 0.1524)
				(type default)
			)
			(layer "F.SilkS")
		)
		(fp_line
			(start -0.7874 0.4064)
			(end -0.7874 -0.4064)
			(stroke
				(width 0.1524)
				(type default)
			)
			(layer "F.SilkS")
		)
		(fp_line
			(start -0.12065 -0.305054)
			(end -0.12065 -0.2794)
			(stroke
				(width 0.1)
				(type default)
			)
			(layer "F.Fab")
		)
		(fp_line
			(start -0.67945 -0.305054)
			(end -0.12065 -0.305054)
			(stroke
				(width 0.1)
				(type default)
			)
			(layer "F.Fab")
		)
		(fp_line
			(start 0.67945 -0.3048)
			(end 0.67945 0.3048)
			(stroke
				(width 0.1)
				(type default)
			)
			(layer "F.Fab")
		)
		(fp_line
			(start 0.12065 -0.3048)
			(end 0.67945 -0.3048)
			(stroke
				(width 0.1)
				(type default)
			)
			(layer "F.Fab")
		)
		(fp_line
			(start 0.12065 -0.2794)
			(end 0.12065 -0.3048)
			(stroke
				(width 0.1)
				(type default)
			)
			(layer "F.Fab")
		)
		(fp_line
			(start -0.12065 -0.2794)
			(end 0.12065 -0.2794)
			(stroke
				(width 0.1)
				(type default)
			)
			(layer "F.Fab")
		)
		(fp_line
			(start 0.120396 0.2794)
			(end -0.12065 0.2794)
			(stroke
				(width 0.1)
				(type default)
			)
			(layer "F.Fab")
		)
		(fp_line
			(start -0.12065 0.2794)
			(end -0.12065 0.3048)
			(stroke
				(width 0.1)
				(type default)
			)
			(layer "F.Fab")
		)
		(fp_line
			(start 0.67945 0.3048)
			(end 0.120396 0.3048)
			(stroke
				(width 0.1)
				(type default)
			)
			(layer "F.Fab")
		)
		(fp_line
			(start 0.120396 0.3048)
			(end 0.120396 0.2794)
			(stroke
				(width 0.1)
				(type default)
			)
			(layer "F.Fab")
		)
		(fp_line
			(start -0.12065 0.3048)
			(end -0.67945 0.3048)
			(stroke
				(width 0.1)
				(type default)
			)
			(layer "F.Fab")
		)
		(fp_line
			(start -0.67945 0.3048)
			(end -0.67945 -0.305054)
			(stroke
				(width 0.1)
				(type default)
			)
			(layer "F.Fab")
		)
		(pad "1" smd circle
			(at -0.40005 0 90)
			(size 0 0)
			(layers "F.Cu" "F.Mask" "F.Paste")
			(net "GPU_FPGA_EROT_RECOV_R_N")
		)
		(pad "2" smd circle
			(at 0.40005 0 90)
			(size 0 0)
			(layers "F.Cu" "F.Mask" "F.Paste")
			(net "GPU_FPGA_EROT_RECOV_N")
		)
	)
)
